# T6G (Grand Teton) — schematic netlist excerpt (pin names and nets, part order shuffled) for the footprints in the layout excerpt that follows; sources: Cadence DE-HDL packaged netlist, KiCad conversion of 04192023_DAF0TMB3IC0_F0TG_MB_C_brd_V02_OCP.brd

R3308  Q_RES  0 5% CHIP  pkg 0402LF  page 143 : A = OCP_V3_2_PRSNT_ALL_R_N ; B = OCP_V3_2_PRSNT_ALL_R1_N
R3497  Q_RES  33.2 1% CHIP  pkg 0402LF  page 129 : A = GPU_FPGA_EROT_RECOV_BUF_R_N ; B = GPU_FPGA_EROT_RECOV_BUF_N

(kicad_pcb
	(version 20260206)
	(generator "pcbnew")
	(generator_version "10.0")
	(general
		(thickness 1.6)
		(legacy_teardrops no)
	)
	(paper "A4")
	(title_block
		(title "04192023_DAF0TMB3IC0_F0TG_MB_C_brd_V02_OCP.brd")
		(comment 1 "Grand Teton / footprints 2524-2525 of 8354")
	)
	(layers
		(0 "F.Cu" signal "TOP")
		(4 "In1.Cu" signal "GND")
		(6 "In2.Cu" signal "IN1")
		(8 "In3.Cu" signal "GND1")
		(10 "In4.Cu" signal "IN2")
		(12 "In5.Cu" signal "GND2")
		(14 "In6.Cu" signal "IN3")
		(16 "In7.Cu" signal "GND3")
		(18 "In8.Cu" signal "VCC")
		(20 "In9.Cu" signal "VCC1")
		(22 "In10.Cu" signal "GND4")
		(24 "In11.Cu" signal "IN4")
		(26 "In12.Cu" signal "GND5")
		(28 "In13.Cu" signal "IN5")
		(30 "In14.Cu" signal "GND6")
		(32 "In15.Cu" signal "IN6")
		(34 "In16.Cu" signal "GND7")
		(2 "B.Cu" signal "BOTTOM")
		(9 "F.Adhes" user "F.Adhesive")
		(11 "B.Adhes" user "B.Adhesive")
		(13 "F.Paste" user "Package Geometry/Pastemask Top")
		(15 "B.Paste" user "Package Geometry/Pastemask Bottom")
		(5 "F.SilkS" user "Ref Des/Silkscreen Top")
		(7 "B.SilkS" user "Ref Des/Silkscreen Bottom")
		(1 "F.Mask" user "Board Geometry/Soldermask Top")
		(3 "B.Mask" user "Board Geometry/Soldermask Bottom")
		(17 "Dwgs.User" user "User.Drawings")
		(19 "Cmts.User" user "User.Comments")
		(21 "Eco1.User" user "User.Eco1")
		(23 "Eco2.User" user "User.Eco2")
		(25 "Edge.Cuts" user "Board Geometry/Outline")
		(27 "Margin" user)
		(31 "F.CrtYd" user "Package Geometry/Place Bound Top")
		(29 "B.CrtYd" user "Package Geometry/Place Bound Bottom")
		(35 "F.Fab" user "Ref Des/Assembly Top")
		(33 "B.Fab" user "Ref Des/Assembly Bottom")
	)
	(footprint ""
		(layer "F.Cu")
		(at 120.396 -433.451)
		(property "Reference" "R3497"
			(at 0 0 0)
			(layer "F.SilkS")
			(hide yes)
			(effects
				(font
					(size 1.27 1.27)
				)
			)
		)
		(property "Value" ""
			(at 0 0 0)
			(layer "F.Fab")
			(effects
				(font
					(size 1.27 1.27)
				)
			)
		)
		(duplicate_pad_numbers_are_jumpers no)
		(fp_line
			(start -0.7874 -0.4064)
			(end 0.7874 -0.4064)
			(stroke
				(width 0.1524)
				(type default)
			)
			(layer "F.SilkS")
		)
		(fp_line
			(start -0.7874 0.4064)
			(end -0.7874 -0.4064)
			(stroke
				(width 0.1524)
				(type default)
			)
			(layer "F.SilkS")
		)
		(fp_line
			(start 0.7874 -0.4064)
			(end 0.7874 0.4064)
			(stroke
				(width 0.1524)
				(type default)
			)
			(layer "F.SilkS")
		)
		(fp_line
			(start 0.7874 0.4064)
			(end -0.7874 0.4064)
			(stroke
				(width 0.1524)
				(type default)
			)
			(layer "F.SilkS")
		)
		(fp_line
			(start -0.67945 -0.305054)
			(end -0.12065 -0.305054)
			(stroke
				(width 0.1)
				(type default)
			)
			(layer "F.Fab")
		)
		(fp_line
			(start -0.67945 0.3048)
			(end -0.67945 -0.305054)
			(stroke
				(width 0.1)
				(type default)
			)
			(layer "F.Fab")
		)
		(fp_line
			(start -0.12065 -0.305054)
			(end -0.12065 -0.2794)
			(stroke
				(width 0.1)
				(type default)
			)
			(layer "F.Fab")
		)
		(fp_line
			(start -0.12065 -0.2794)
			(end 0.12065 -0.2794)
			(stroke
				(width 0.1)
				(type default)
			)
			(layer "F.Fab")
		)
		(fp_line
			(start -0.12065 0.2794)
			(end -0.12065 0.3048)
			(stroke
				(width 0.1)
				(type default)
			)
			(layer "F.Fab")
		)
		(fp_line
			(start -0.12065 0.3048)
			(end -0.67945 0.3048)
			(stroke
				(width 0.1)
				(type default)
			)
			(layer "F.Fab")
		)
		(fp_line
			(start 0.120396 0.2794)
			(end -0.12065 0.2794)
			(stroke
				(width 0.1)
				(type default)
			)
			(layer "F.Fab")
		)
		(fp_line
			(start 0.120396 0.3048)
			(end 0.120396 0.2794)
			(stroke
				(width 0.1)
				(type default)
			)
			(layer "F.Fab")
		)
		(fp_line
			(start 0.12065 -0.3048)
			(end 0.67945 -0.3048)
			(stroke
				(width 0.1)
				(type default)
			)
			(layer "F.Fab")
		)
		(fp_line
			(start 0.12065 -0.2794)
			(end 0.12065 -0.3048)
			(stroke
				(width 0.1)
				(type default)
			)
			(layer "F.Fab")
		)
		(fp_line
			(start 0.67945 -0.3048)
			(end 0.67945 0.3048)
			(stroke
				(width 0.1)
				(type default)
			)
			(layer "F.Fab")
		)
		(fp_line
			(start 0.67945 0.3048)
			(end 0.120396 0.3048)
			(stroke
				(width 0.1)
				(type default)
			)
			(layer "F.Fab")
		)
		(pad "1" smd circle
			(at -0.40005 0)
			(size 0 0)
			(layers "F.Cu" "F.Mask" "F.Paste")
			(net "GPU_FPGA_EROT_RECOV_BUF_R_N")
		)
		(pad "2" smd circle
			(at 0.40005 0)
			(size 0 0)
			(layers "F.Cu" "F.Mask" "F.Paste")
			(net "GPU_FPGA_EROT_RECOV_BUF_N")
		)
	)
	(footprint ""
		(layer "F.Cu")
		(at 148.73859 -98.755708 90)
		(property "Reference" "R3308"
			(at 0 0 90)
			(layer "F.SilkS")
			(hide yes)
			(effects
				(font
					(size 1.27 1.27)
				)
			)
		)
		(property "Value" ""
			(at 0 0 90)
			(layer "F.Fab")
			(effects
				(font
					(size 1.27 1.27)
				)
			)
		)
		(duplicate_pad_numbers_are_jumpers no)
		(fp_line
			(start 0.7874 -0.4064)
			(end 0.7874 0.4064)
			(stroke
				(width 0.1524)
				(type default)
			)
			(layer "F.SilkS")
		)
		(fp_line
			(start -0.7874 -0.4064)
			(end 0.7874 -0.4064)
			(stroke
				(width 0.1524)
				(type default)
			)
			(layer "F.SilkS")
		)
		(fp_line
			(start 0.7874 0.4064)
			(end -0.7874 0.4064)
			(stroke
				(width 0.1524)
				(type default)
			)
			(layer "F.SilkS")
		)
		(fp_line
			(start -0.7874 0.4064)
			(end -0.7874 -0.4064)
			(stroke
				(width 0.1524)
				(type default)
			)
			(layer "F.SilkS")
		)
		(fp_line
			(start -0.12065 -0.305054)
			(end -0.12065 -0.2794)
			(stroke
				(width 0.1)
				(type default)
			)
			(layer "F.Fab")
		)
		(fp_line
			(start -0.67945 -0.305054)
			(end -0.12065 -0.305054)
			(stroke
				(width 0.1)
				(type default)
			)
			(layer "F.Fab")
		)
		(fp_line
			(start 0.67945 -0.3048)
			(end 0.67945 0.3048)
			(stroke
				(width 0.1)
				(type default)
			)
			(layer "F.Fab")
		)
		(fp_line
			(start 0.12065 -0.3048)
			(end 0.67945 -0.3048)
			(stroke
				(width 0.1)
				(type default)
			)
			(layer "F.Fab")
		)
		(fp_line
			(start 0.12065 -0.2794)
			(end 0.12065 -0.3048)
			(stroke
				(width 0.1)
				(type default)
			)
			(layer "F.Fab")
		)
		(fp_line
			(start -0.12065 -0.2794)
			(end 0.12065 -0.2794)
			(stroke
				(width 0.1)
				(type default)
			)
			(layer "F.Fab")
		)
		(fp_line
			(start 0.120396 0.2794)
			(end -0.12065 0.2794)
			(stroke
				(width 0.1)
				(type default)
			)
			(layer "F.Fab")
		)
		(fp_line
			(start -0.12065 0.2794)
			(end -0.12065 0.3048)
			(stroke
				(width 0.1)
				(type default)
			)
			(layer "F.Fab")
		)
		(fp_line
			(start 0.67945 0.3048)
			(end 0.120396 0.3048)
			(stroke
				(width 0.1)
				(type default)
			)
			(layer "F.Fab")
		)
		(fp_line
			(start 0.120396 0.3048)
			(end 0.120396 0.2794)
			(stroke
				(width 0.1)
				(type default)
			)
			(layer "F.Fab")
		)
		(fp_line
			(start -0.12065 0.3048)
			(end -0.67945 0.3048)
			(stroke
				(width 0.1)
				(type default)
			)
			(layer "F.Fab")
		)
		(fp_line
			(start -0.67945 0.3048)
			(end -0.67945 -0.305054)
			(stroke
				(width 0.1)
				(type default)
			)
			(layer "F.Fab")
		)
		(pad "1" smd circle
			(at -0.40005 0 90)
			(size 0 0)
			(layers "F.Cu" "F.Mask" "F.Paste")
			(net "OCP_V3_2_PRSNT_ALL_R_N")
		)
		(pad "2" smd circle
			(at 0.40005 0 90)
			(size 0 0)
			(layers "F.Cu" "F.Mask" "F.Paste")
			(net "OCP_V3_2_PRSNT_ALL_R1_N")
		)
	)
)
